# S9S_MB_2U (Grand Teton) — schematic netlist excerpt (pin names and nets, part order shuffled) for the footprints in the layout excerpt that follows; sources: Cadence DE-HDL packaged netlist, KiCad conversion of 03242023_DA0F0TMBIJ0_F0T_Motherboard_J_brd_V01_OCP.brd

R4164  Q_RES  4.7K 5% CHIP  pkg 0402LF  page 145 : A = P3V3_AUX ; B = GPU_3V3IO_RSVD1_N
C696  Q_CAP_DIFFBUS  DIFF BUS_0.22UF 6.3V 20% X6S  pkg C0201  page 177 : \1\ = P5E_CPU1_PE4_TX_C_DN<6> ; \2\ = P5E_CPU1_PE4_TX_DN<6>
PR3926  Q_RES  75K 0.1% CHIP  pkg 0402LF  page 301 : A = P12V_PSU ; B = HSC_VSENSE

(kicad_pcb
	(version 20260206)
	(generator "pcbnew")
	(generator_version "10.0")
	(general
		(thickness 1.6)
		(legacy_teardrops no)
	)
	(paper "A4")
	(title_block
		(title "03242023_DA0F0TMBIJ0_F0T_Motherboard_J_brd_V01_OCP.brd")
		(comment 1 "Grand Teton / footprints 3439-3441 of 6105")
	)
	(layers
		(0 "F.Cu" signal "TOP")
		(4 "In1.Cu" signal "GND")
		(6 "In2.Cu" signal "IN1")
		(8 "In3.Cu" signal "GND1")
		(10 "In4.Cu" signal "IN2")
		(12 "In5.Cu" signal "GND2")
		(14 "In6.Cu" signal "IN3")
		(16 "In7.Cu" signal "GND3")
		(18 "In8.Cu" signal "VCC")
		(20 "In9.Cu" signal "VCC1")
		(22 "In10.Cu" signal "GND4")
		(24 "In11.Cu" signal "IN4")
		(26 "In12.Cu" signal "GND5")
		(28 "In13.Cu" signal "IN5")
		(30 "In14.Cu" signal "GND6")
		(32 "In15.Cu" signal "IN6")
		(34 "In16.Cu" signal "GND7")
		(2 "B.Cu" signal "BOTTOM")
		(9 "F.Adhes" user "F.Adhesive")
		(11 "B.Adhes" user "B.Adhesive")
		(13 "F.Paste" user "Package Geometry/Pastemask Top")
		(15 "B.Paste" user "Package Geometry/Pastemask Bottom")
		(5 "F.SilkS" user "Ref Des/Silkscreen Top")
		(7 "B.SilkS" user "Ref Des/Silkscreen Bottom")
		(1 "F.Mask" user "Board Geometry/Soldermask Top")
		(3 "B.Mask" user "Board Geometry/Soldermask Bottom")
		(17 "Dwgs.User" user "User.Drawings")
		(19 "Cmts.User" user "User.Comments")
		(21 "Eco1.User" user "User.Eco1")
		(23 "Eco2.User" user "User.Eco2")
		(25 "Edge.Cuts" user "Board Geometry/Outline")
		(27 "Margin" user)
		(31 "F.CrtYd" user "Package Geometry/Place Bound Top")
		(29 "B.CrtYd" user "Package Geometry/Place Bound Bottom")
		(35 "F.Fab" user "Ref Des/Assembly Top")
		(33 "B.Fab" user "Ref Des/Assembly Bottom")
	)
	(footprint ""
		(layer "F.Cu")
		(at 369.129818 -387.779006 180)
		(property "Reference" "R4164"
			(at 0 0 180)
			(layer "F.SilkS")
			(hide yes)
			(effects
				(font
					(size 1.27 1.27)
				)
			)
		)
		(property "Value" ""
			(at 0 0 180)
			(layer "F.Fab")
			(effects
				(font
					(size 1.27 1.27)
				)
			)
		)
		(duplicate_pad_numbers_are_jumpers no)
		(fp_line
			(start 0.7874 0.4064)
			(end -0.7874 0.4064)
			(stroke
				(width 0.1524)
				(type default)
			)
			(layer "F.SilkS")
		)
		(fp_line
			(start 0.7874 -0.4064)
			(end 0.7874 0.4064)
			(stroke
				(width 0.1524)
				(type default)
			)
			(layer "F.SilkS")
		)
		(fp_line
			(start -0.7874 0.4064)
			(end -0.7874 -0.4064)
			(stroke
				(width 0.1524)
				(type default)
			)
			(layer "F.SilkS")
		)
		(fp_line
			(start -0.7874 -0.4064)
			(end 0.7874 -0.4064)
			(stroke
				(width 0.1524)
				(type default)
			)
			(layer "F.SilkS")
		)
		(fp_line
			(start 0.67945 0.3048)
			(end 0.120396 0.3048)
			(stroke
				(width 0.1)
				(type default)
			)
			(layer "F.Fab")
		)
		(fp_line
			(start 0.67945 -0.3048)
			(end 0.67945 0.3048)
			(stroke
				(width 0.1)
				(type default)
			)
			(layer "F.Fab")
		)
		(fp_line
			(start 0.12065 -0.2794)
			(end 0.12065 -0.3048)
			(stroke
				(width 0.1)
				(type default)
			)
			(layer "F.Fab")
		)
		(fp_line
			(start 0.12065 -0.3048)
			(end 0.67945 -0.3048)
			(stroke
				(width 0.1)
				(type default)
			)
			(layer "F.Fab")
		)
		(fp_line
			(start 0.120396 0.3048)
			(end 0.120396 0.2794)
			(stroke
				(width 0.1)
				(type default)
			)
			(layer "F.Fab")
		)
		(fp_line
			(start 0.120396 0.2794)
			(end -0.12065 0.2794)
			(stroke
				(width 0.1)
				(type default)
			)
			(layer "F.Fab")
		)
		(fp_line
			(start -0.12065 0.3048)
			(end -0.67945 0.3048)
			(stroke
				(width 0.1)
				(type default)
			)
			(layer "F.Fab")
		)
		(fp_line
			(start -0.12065 0.2794)
			(end -0.12065 0.3048)
			(stroke
				(width 0.1)
				(type default)
			)
			(layer "F.Fab")
		)
		(fp_line
			(start -0.12065 -0.2794)
			(end 0.12065 -0.2794)
			(stroke
				(width 0.1)
				(type default)
			)
			(layer "F.Fab")
		)
		(fp_line
			(start -0.12065 -0.305054)
			(end -0.12065 -0.2794)
			(stroke
				(width 0.1)
				(type default)
			)
			(layer "F.Fab")
		)
		(fp_line
			(start -0.67945 0.3048)
			(end -0.67945 -0.305054)
			(stroke
				(width 0.1)
				(type default)
			)
			(layer "F.Fab")
		)
		(fp_line
			(start -0.67945 -0.305054)
			(end -0.12065 -0.305054)
			(stroke
				(width 0.1)
				(type default)
			)
			(layer "F.Fab")
		)
		(pad "1" smd circle
			(at -0.40005 0 180)
			(size 0 0)
			(layers "F.Cu" "F.Mask" "F.Paste")
			(net "P3V3_AUX")
		)
		(pad "2" smd circle
			(at 0.40005 0 180)
			(size 0 0)
			(layers "F.Cu" "F.Mask" "F.Paste")
			(net "GPU_3V3IO_RSVD1_N")
		)
	)
	(footprint ""
		(layer "F.Cu")
		(at 67.680078 -408.517344 -90)
		(property "Reference" "C696"
			(at 0 0 270)
			(layer "F.SilkS")
			(hide yes)
			(effects
				(font
					(size 1.27 1.27)
				)
			)
		)
		(property "Value" ""
			(at 0 0 270)
			(layer "F.Fab")
			(effects
				(font
					(size 1.27 1.27)
				)
			)
		)
		(duplicate_pad_numbers_are_jumpers no)
		(fp_line
			(start -0.299974 0.150114)
			(end -0.299974 -0.150114)
			(stroke
				(width 0.1)
				(type default)
			)
			(layer "F.Fab")
		)
		(fp_line
			(start 0.299974 0.150114)
			(end -0.299974 0.150114)
			(stroke
				(width 0.1)
				(type default)
			)
			(layer "F.Fab")
		)
		(fp_line
			(start -0.299974 -0.150114)
			(end 0.299974 -0.150114)
			(stroke
				(width 0.1)
				(type default)
			)
			(layer "F.Fab")
		)
		(fp_line
			(start 0.299974 -0.150114)
			(end 0.299974 0.150114)
			(stroke
				(width 0.1)
				(type default)
			)
			(layer "F.Fab")
		)
		(pad "1" smd rect
			(at -0.2667 0 270)
			(size 0.3048 0.381)
			(layers "F.Cu" "F.Mask" "F.Paste")
			(net "P5E_CPU1_PE4_TX_C_DN<6>")
		)
		(pad "2" smd rect
			(at 0.2667 0 270)
			(size 0.3048 0.381)
			(layers "F.Cu" "F.Mask" "F.Paste")
			(net "P5E_CPU1_PE4_TX_DN<6>")
		)
	)
	(footprint ""
		(layer "F.Cu")
		(at 185.230008 -408.912822 180)
		(property "Reference" "PR3926"
			(at 0 0 180)
			(layer "F.SilkS")
			(hide yes)
			(effects
				(font
					(size 1.27 1.27)
				)
			)
		)
		(property "Value" ""
			(at 0 0 180)
			(layer "F.Fab")
			(effects
				(font
					(size 1.27 1.27)
				)
			)
		)
		(duplicate_pad_numbers_are_jumpers no)
		(fp_line
			(start 0.7874 0.4064)
			(end -0.7874 0.4064)
			(stroke
				(width 0.1524)
				(type default)
			)
			(layer "F.SilkS")
		)
		(fp_line
			(start 0.7874 -0.4064)
			(end 0.7874 0.4064)
			(stroke
				(width 0.1524)
				(type default)
			)
			(layer "F.SilkS")
		)
		(fp_line
			(start -0.7874 0.4064)
			(end -0.7874 -0.4064)
			(stroke
				(width 0.1524)
				(type default)
			)
			(layer "F.SilkS")
		)
		(fp_line
			(start -0.7874 -0.4064)
			(end 0.7874 -0.4064)
			(stroke
				(width 0.1524)
				(type default)
			)
			(layer "F.SilkS")
		)
		(fp_line
			(start 0.67945 0.3048)
			(end 0.120396 0.3048)
			(stroke
				(width 0.1)
				(type default)
			)
			(layer "F.Fab")
		)
		(fp_line
			(start 0.67945 -0.3048)
			(end 0.67945 0.3048)
			(stroke
				(width 0.1)
				(type default)
			)
			(layer "F.Fab")
		)
		(fp_line
			(start 0.12065 -0.2794)
			(end 0.12065 -0.3048)
			(stroke
				(width 0.1)
				(type default)
			)
			(layer "F.Fab")
		)
		(fp_line
			(start 0.12065 -0.3048)
			(end 0.67945 -0.3048)
			(stroke
				(width 0.1)
				(type default)
			)
			(layer "F.Fab")
		)
		(fp_line
			(start 0.120396 0.3048)
			(end 0.120396 0.2794)
			(stroke
				(width 0.1)
				(type default)
			)
			(layer "F.Fab")
		)
		(fp_line
			(start 0.120396 0.2794)
			(end -0.12065 0.2794)
			(stroke
				(width 0.1)
				(type default)
			)
			(layer "F.Fab")
		)
		(fp_line
			(start -0.12065 0.3048)
			(end -0.67945 0.3048)
			(stroke
				(width 0.1)
				(type default)
			)
			(layer "F.Fab")
		)
		(fp_line
			(start -0.12065 0.2794)
			(end -0.12065 0.3048)
			(stroke
				(width 0.1)
				(type default)
			)
			(layer "F.Fab")
		)
		(fp_line
			(start -0.12065 -0.2794)
			(end 0.12065 -0.2794)
			(stroke
				(width 0.1)
				(type default)
			)
			(layer "F.Fab")
		)
		(fp_line
			(start -0.12065 -0.305054)
			(end -0.12065 -0.2794)
			(stroke
				(width 0.1)
				(type default)
			)
			(layer "F.Fab")
		)
		(fp_line
			(start -0.67945 0.3048)
			(end -0.67945 -0.305054)
			(stroke
				(width 0.1)
				(type default)
			)
			(layer "F.Fab")
		)
		(fp_line
			(start -0.67945 -0.305054)
			(end -0.12065 -0.305054)
			(stroke
				(width 0.1)
				(type default)
			)
			(layer "F.Fab")
		)
		(pad "1" smd circle
			(at -0.40005 0 180)
			(size 0 0)
			(layers "F.Cu" "F.Mask" "F.Paste")
			(net "P12V_PSU")
		)
		(pad "2" smd circle
			(at 0.40005 0 180)
			(size 0 0)
			(layers "F.Cu" "F.Mask" "F.Paste")
			(net "HSC_VSENSE")
		)
	)
)
